FILE_TYPE = CONNECTIVITY;
{Allegro Design Entry HDL 17.4-2019 S026 (4007227) 1/17/2022}
"PAGE_NUMBER" = 273;
0"NC";
1"P3V3_AUX\g";
2"GND\g";
3"GND\g";
4"P3V3_AUX\g";
5"GND\g";
6"P12V_AUX\g";
7"GND\g";
8"P12V_AUX\g";
9"P12V_AUX\g";
10"GND\g";
11"P3V3_AUX\g";
12"GND\g";
13"GND\g";
14"P1V8_AUX\g";
15"GND\g";
16"GND\g";
17"GND\g";
18"P3V3\g";
19"GND\g";
20"P12V_AUX\g";
21"P3V3\g";
22"P5V\g";
23"GND\g";
24"GND\g";
25"GND\g";
26"GND\g";
27"GND\g";
28"GND\g";
29"P5V\g";
30"GND\g";
31"GND\g";
32"P3V3_AUX\g";
33"PWRGD_P5V_R";
34"PWRGD_P5V_R1";
35"PWRGD_P3V3_R1";
36"P3V3\g";
37"GND\g";
38"P5V_AUX\g";
39"GND\g";
40"P5V\g";
41"GND\g";
42"P3V3_AUX\g";
43"GND\g";
44"P3V3\g";
45"P5V\g";
46"SW_P3V3_EN";
47"VR_P5V_EN_D";
48"SW_P3V3_EN_R";
49"VR_P5V_EN_D_R";
50"VR_P5V_EN";
51"VR_P5V_EN_N";
52"PWRGD_P3V3_R2";
53"PWRGD_P3V3_EN";
54"PWRGD_P3V3_EN_N";
55"VR_P5V_EN_D_R1";
56"FM_P5V_EN";
57"PWRGD_P5V_N";
58"PWRGD_P5V_R2";
59"SW_P3V3_EN_ISO";
60"SW_P3V3_EN_ISO_R";
61"PWRGD_P5V_R_N";
62"VR_P5V_EN_N";
63"SW_P3V3_EN_N";
64"PWRGD_P3V3_EN_R";
%"Q_RES"
"2","(-5125,5550)","0","pure_quanta","I10";
;
LOCATION"R336"
$SEC"1"
CDS_SEC"1"
WATTAGE"1/16W"
VALUE"100K"
TOLERANCE"1%"
MATERIAL"CHIP"
PACK_TYPE"0402LF"
PART_NUMBER"CS41002FB09"
CDS_LIB"pure_quanta"
BOM_COST"VR_SYSTEM "
REUSE_ID"1";
"A"
$PN"1"6;
"B"
$PN"2"51;
%"P1V0_AUX"
"1","(-1450,3275)","0","pure_quanta_power","I100";
;
HDL_POWER"P3V3_AUX"
BOM_COST"VR_SYSTEM "
CDS_LIB"pure_quanta_power";
"A"1;
%"UNIVERSAL_GND"
"1","(-1450,2175)","0","pure_quanta_power","I101";
;
VOLTAGE"0"
BOM_COST"VR_SYSTEM "
CDS_LIB"pure_quanta_power"
HDL_POWER"GND";
"A"2;
%"Q_RES"
"1","(-625,2850)","0","pure_quanta","I102";
;
LOCATION"R494"
SEC"1"
TOLERANCE"5%"
VALUE"0"
MATERIAL"CHIP"
PACK_TYPE"0402LF"
PART_NUMBER"CS00002JB13"
WATTAGE"1/16W"
CDS_LIB"pure_quanta"
SEC_TYPE"0402LF";
"B"
$PN"2"57;
"A"
$PN"1"61;
%"UNIVERSAL_GND"
"1","(300,2275)","0","pure_quanta_power","I103";
;
VOLTAGE"0"
BOM_COST"VR_SYSTEM "
CDS_LIB"pure_quanta_power"
HDL_POWER"GND";
"A"3;
%"Q_RES"
"2","(300,3325)","2","pure_quanta","I104";
;
LOCATION"R552"
$SEC"1"
CDS_SEC"1"
VALUE"4.7K"
PACK_TYPE"0402LF"
TOLERANCE"5%"
WATTAGE"1/16W"
MATERIAL"CHIP"
PART_NUMBER"CS24702JB10"
CDS_LIB"pure_quanta";
"A"
$PN"1"4;
"B"
$PN"2"58;
%"P1V0_AUX"
"1","(300,3575)","0","pure_quanta_power","I105";
;
HDL_POWER"P3V3_AUX"
BOM_COST"VR_SYSTEM "
CDS_LIB"pure_quanta_power";
"A"4;
%"MOSFET_NCH_DUAL"
"1","(-1125,4025)","0","pure_quanta","I107";
;
LOCATION"Q3"
SEC"1"
MATERIAL"IC"
VALUE"PJT138K"
PART_TYPE"SMLF"
PART_NUMBER"BAM138K0003"
CDS_LIB"pure_quanta"
NEEDS_NO_SIZE"TRUE"
CDS_LMAN_SYM_OUTLINE"-150,150,150,-150"
SEC_TYPE"";
"D1"
$PN"6"63;
"G1"
$PN"2"48;
"S1"
$PN"1"5;
%"MOSFET_NCH_DUAL"
"2","(-325,4075)","0","pure_quanta","I108";
;
LOCATION"Q3"
SEC"2"
PART_TYPE"SMLF"
MATERIAL"IC"
VALUE"PJT138K"
PART_NUMBER"BAM138K0003"
CDS_LMAN_SYM_OUTLINE"-150,150,150,-150"
NEEDS_NO_SIZE"TRUE"
CDS_LIB"pure_quanta"
SEC_TYPE"";
"S2"
$PN"4"7;
"G2"
$PN"5"63;
"D2"
$PN"3"59;
%"UNIVERSAL_GND"
"1","(-1075,3550)","0","pure_quanta_power","I109";
;
CDS_LIB"pure_quanta_power"
BOM_COST"VR_SYSTEM "
VOLTAGE"0"
HDL_POWER"GND";
"A"5;
%"UNIVERSAL_POWER"
"1","(-5125,5825)","0","pure_quanta_power","I11";
;
HDL_POWER"P12V_AUX"
BOM_COST"VR_SYSTEM "
CDS_LIB"pure_quanta_power";
"A"6;
%"UNIVERSAL_GND"
"1","(-275,3600)","0","pure_quanta_power","I110";
;
CDS_LIB"pure_quanta_power"
VOLTAGE"0"
BOM_COST"VR_SYSTEM "
HDL_POWER"GND";
"A"7;
%"Q_RES"
"2","(-1075,4575)","0","pure_quanta","I111";
;
LOCATION"R554"
SEC"1"
MATERIAL"CHIP"
PACK_TYPE"0402LF"
WATTAGE"1/16W"
TOLERANCE"1%"
VALUE"100K"
PART_NUMBER"CS41002FB09"
SEC_TYPE"0402LF"
CDS_LIB"pure_quanta";
"A"
$PN"1"8;
"B"
$PN"2"63;
%"UNIVERSAL_POWER"
"1","(-1075,4950)","0","pure_quanta_power","I112";
;
HDL_POWER"P12V_AUX"
BOM_COST"VR_SYSTEM "
CDS_LIB"pure_quanta_power";
"A"8;
%"Q_RES"
"2","(-275,4575)","0","pure_quanta","I113";
;
LOCATION"R569"
$SEC"1"
CDS_SEC"1"
VALUE"1K"
PACK_TYPE"0402LF"
MATERIAL"CHIP"
TOLERANCE"1%"
WATTAGE"1/16W"
PART_NUMBER"CS21002FB06"
CDS_LIB"pure_quanta";
"A"
$PN"1"60;
"B"
$PN"2"59;
%"Q_RES"
"2","(-550,4925)","2","pure_quanta","I114";
;
LOCATION"R568"
$SEC"1"
CDS_SEC"1"
VALUE"10K"
PACK_TYPE"0402LF"
MATERIAL"CHIP"
WATTAGE"1/16W"
TOLERANCE"1%"
PART_NUMBER"CS31002FB08"
CDS_LIB"pure_quanta";
"A"
$PN"1"9;
"B"
$PN"2"60;
%"UNIVERSAL_POWER"
"1","(-550,5300)","0","pure_quanta_power","I115";
;
HDL_POWER"P12V_AUX"
CDS_LIB"pure_quanta_power"
BOM_COST"VR_SYSTEM ";
"A"9;
%"Q_CAP"
"1","(325,4575)","0","pure_quanta","I116";
;
LOCATION"C29"
$SEC"1"
CDS_SEC"1"
PACK_TYPE"C0402"
VALUE"0.22UF"
TOLERANCE"10%"
MATERIAL"X7R"
VOLTAGE"25V"
PART_NUMBER"CH4224K1B01"
CDS_LIB"pure_quanta";
"B"
$PN"2"10;
"A"
$PN"1"60;
%"UNIVERSAL_GND"
"1","(325,4200)","0","pure_quanta_power","I117";
;
VOLTAGE"0"
BOM_COST"VR_SYSTEM "
CDS_LIB"pure_quanta_power"
HDL_POWER"GND";
"A"10;
%"Q_RES"
"2","(-5500,2725)","0","pure_quanta","I120";
;
LOCATION"R1492"
$SEC"1"
CDS_SEC"1"
PACK_TYPE"0402LF"
WATTAGE"1/16W"
VALUE"10K"
TOLERANCE"5%"
MATERIAL"CHIP"
PART_NUMBER"CS31002JB08"
CDS_LIB"pure_quanta"
BOM_COST"VR_SYSTEM";
"A"
$PN"1"11;
"B"
$PN"2"54;
%"UNIVERSAL_POWER"
"1","(-5500,3175)","0","pure_quanta_power","I121";
;
HDL_POWER"P3V3_AUX"
CDS_LIB"pure_quanta_power"
BOM_COST"VR_SYSTEM";
"A"11;
%"UNIVERSAL_GND"
"1","(-5425,2275)","7","pure_quanta_power","I122";
;
BOM_COST"VR_SYSTEM"
CDS_LIB"pure_quanta_power"
HDL_POWER"GND";
"A"12;
%"BSS138DW7F"
"1","(-5050,2225)","0","pure_quanta","I123";
;
LOCATION"Q27"
$SEC"1"
CDS_SEC"1"
MATERIAL"IC"
PART_TYPE"SMLF"
VALUE"BSS138DW-7-F"
PART_NUMBER"BAM01380032"
CDS_LIB"pure_quanta"
NEEDS_NO_SIZE"TRUE";
"D2"
$PN"3"35;
"D1"
$PN"6"54;
"S2"
$PN"4"13;
"G2"
$PN"5"54;
"G1"
$PN"2"53;
"S1"
$PN"1"12;
%"UNIVERSAL_GND"
"1","(-4675,2275)","1","pure_quanta_power","I124";
;
BOM_COST"VR_SYSTEM"
CDS_LIB"pure_quanta_power"
HDL_POWER"GND";
"A"13;
%"Q_RES"
"2","(-4600,2850)","0","pure_quanta","I125";
;
LOCATION"R1493"
$SEC"1"
CDS_SEC"1"
PACK_TYPE"0402LF"
MATERIAL"CHIP"
WATTAGE"1/16W"
TOLERANCE"5%"
VALUE"10K"
PART_NUMBER"CS31002JB08"
BOM_COST"VR_SYSTEM"
CDS_LIB"pure_quanta";
"A"
$PN"1"14;
"B"
$PN"2"35;
%"P1V0_AUX"
"1","(-4600,3125)","0","pure_quanta_power","I126";
;
HDL_POWER"P1V8_AUX"
CDS_LIB"pure_quanta_power";
"A"14;
%"UNIVERSAL_GND"
"1","(-4350,4775)","0","pure_quanta_power","I13";
;
VOLTAGE"0"
CDS_LIB"pure_quanta_power"
BOM_COST"VR_SYSTEM "
HDL_POWER"GND";
"A"15;
%"Q_RES"
"1","(-3925,2600)","0","pure_quanta","I130";
;
LOCATION"R1362"
$SEC"1"
CDS_SEC"1"
VALUE"33"
PART_NUMBER"CS03302JB10"
CDS_LIB"pure_quanta"
BOM_COST"MEM"
WATTAGE"1/16W"
MATERIAL"CHIP"
TOLERANCE"5%"
PACK_TYPE"0402LF";
"B"
$PN"2"52;
"A"
$PN"1"35;
%"APX80929SAG7"
"1","(-7125,2325)","2","pure_quanta","I131";
;
LOCATION"U6006"
SEC"1"
VALUE"APX809-29SAG-7"
PART_TYPE"SMLF"
MATERIAL"IC"
PART_NUMBER"AL080929000"
CDS_LIB"pure_quanta"
NEEDS_NO_SIZE"TRUE"
CDS_LMAN_SYM_OUTLINE"-225,200,225,-200"
SEC_TYPE"";
"GND"
$PN"1"17;
"RESET_L \B"
$PN"2"64;
"VCC"
$PN"3"36;
%"UNIVERSAL_POWER"
"1","(-7575,2625)","0","pure_quanta_power","I132";
;
HDL_POWER"P3V3"
BOM_COST"VR_SYSTEM"
CDS_LIB"pure_quanta_power";
"A"36;
%"Q_CAP"
"1","(-7575,2125)","0","pure_quanta","I133";
;
LOCATION"C6500"
$SEC"1"
CDS_SEC"1"
MATERIAL"X7R"
TOLERANCE"10%"
VALUE"0.1UF"
VOLTAGE"25V"
PACK_TYPE"0402"
PART_NUMBER"CH4104K1B00"
CDS_LIB"pure_quanta";
"B"
$PN"2"16;
"A"
$PN"1"36;
%"UNIVERSAL_GND"
"1","(-7575,1875)","0","pure_quanta_power","I134";
;
BOM_COST"VR_SYSTEM "
VOLTAGE"0"
CDS_LIB"pure_quanta_power"
HDL_POWER"GND";
"A"16;
%"UNIVERSAL_GND"
"1","(-6600,2325)","0","pure_quanta_power","I135";
;
CDS_LIB"pure_quanta_power"
BOM_COST"VR_SYSTEM "
VOLTAGE"0"
HDL_POWER"GND";
"A"17;
%"Q_RES"
"1","(-5950,2225)","0","pure_quanta","I136";
;
LOCATION"R6500"
SEC"1"
PACK_TYPE"0402LF"
VALUE"0"
TOLERANCE"5%"
MATERIAL"CHIP"
PART_NUMBER"CS00002JB13"
SEC_TYPE"0402LF"
CDS_LIB"pure_quanta"
WATTAGE"1/16W";
"B"
$PN"2"53;
"A"
$PN"1"64;
%"UNIVERSAL_POWER"
"1","(-6200,2775)","0","pure_quanta_power","I138";
;
HDL_POWER"P3V3"
CDS_LIB"pure_quanta_power"
BOM_COST"VR_SYSTEM";
"A"18;
%"Q_RES"
"2","(-6175,2050)","2","pure_quanta","I139";
;
LOCATION"R6501"
SEC"1"
VALUE"100K"
MATERIAL"CHIP"
TOLERANCE"1%"
PACK_TYPE"0402LF"
PART_NUMBER"CS41002FB09"
SEC_TYPE"0402LF"
CDS_LIB"pure_quanta"
WATTAGE"1/16W";
"A"
$PN"1"64;
"B"
$PN"2"19;
%"MOSFET_NCH_DUAL"
"2","(-4400,5325)","0","pure_quanta","I14";
;
LOCATION"Q37"
$SEC"2"
CDS_SEC"2"
VALUE"PJT138K"
MATERIAL"IC"
PART_TYPE"SMLF"
PART_NUMBER"BAM138K0003"
NEEDS_NO_SIZE"TRUE"
CDS_LMAN_SYM_OUTLINE"-150,150,150,-150"
CDS_LIB"pure_quanta";
"S2"
$PN"4"15;
"G2"
$PN"5"51;
"D2"
$PN"3"55;
%"UNIVERSAL_GND"
"1","(-6175,1850)","0","pure_quanta_power","I140";
;
BOM_COST"VR_SYSTEM "
VOLTAGE"0"
CDS_LIB"pure_quanta_power"
HDL_POWER"GND";
"A"19;
%"Q_RES"
"2","(-6200,2550)","0","pure_quanta","I141";
;
LOCATION"R1491"
SEC"1"
VALUE"10K"
TOLERANCE"5%"
PACK_TYPE"0402LF"
WATTAGE"1/16W"
MATERIAL"EMPTY"
PART_NUMBER"CS31002JB08"
SEC_TYPE"0402LF"
CDS_LIB"pure_quanta";
"A"
$PN"1"18;
"B"
$PN"2"64;
%"Q_RES"
"1","(-5575,6625)","0","pure_quanta","I15";
;
LOCATION"R335"
$SEC"1"
CDS_SEC"1"
TOLERANCE"1%"
PACK_TYPE"0402LF"
MATERIAL"CHIP"
VALUE"10K"
WATTAGE"1/16W"
PART_NUMBER"CS31002FB08"
CDS_LIB"pure_quanta"
BOM_COST"VR_SYSTEM "
REUSE_ID"3";
"B"
$PN"2"49;
"A"
$PN"1"20;
%"UNIVERSAL_POWER"
"1","(-5975,6925)","0","pure_quanta_power","I16";
;
HDL_POWER"P12V_AUX"
BOM_COST"VR_SYSTEM "
CDS_LIB"pure_quanta_power";
"A"20;
%"UNIVERSAL_GND"
"1","(-5975,7225)","0","pure_quanta_power","I17";
;
BOM_COST"VR_SYSTEM "
CDS_LIB"pure_quanta_power"
VOLTAGE"0"
HDL_POWER"GND";
"A"37;
%"Q_CAP"
"1","(-5975,7575)","2","pure_quanta","I18";
;
LOCATION"C1042"
$SEC"1"
CDS_SEC"1"
PACK_TYPE"C0402"
TOLERANCE"10%"
VALUE"100NF"
VOLTAGE"50V"
MATERIAL"X7R"
PART_NUMBER"CH4106K1B01"
CDS_LIB"pure_quanta"
BOM_COST"VR_SYSTEM "
REUSE_ID"81";
"B"
$PN"2"37;
"A"
$PN"1"38;
%"Q_CAP"
"1","(-5650,7575)","2","pure_quanta","I19";
;
LOCATION"C1170"
$SEC"1"
CDS_SEC"1"
VALUE"10UF"
PACK_TYPE"C0805"
MATERIAL"X6S"
TOLERANCE"10%"
VOLTAGE"16V"
PART_NUMBER"CH6103KEA00"
CDS_LIB"pure_quanta"
BOM_COST"VR_SYSTEM "
REUSE_ID"6";
"B"
$PN"2"37;
"A"
$PN"1"38;
%"Q_CAP"
"1","(-5325,7575)","2","pure_quanta","I20";
;
LOCATION"C57"
$SEC"1"
CDS_SEC"1"
TOLERANCE"10%"
MATERIAL"EMPTY"
VALUE"10UF"
VOLTAGE"16V"
PACK_TYPE"C0805"
PART_NUMBER"CH6103KEA00"
CDS_LIB"pure_quanta"
BOM_COST"VR_SYSTEM "
REUSE_ID"8";
"B"
$PN"2"37;
"A"
$PN"1"38;
%"P1V0_AUX"
"1","(-5151,7874)","0","pure_quanta_power","I21";
;
HDL_POWER"P5V_AUX"
BOM_COST"VR_SYSTEM "
CDS_LIB"pure_quanta_power";
"A"38;
%"Q_RES"
"2","(-4350,6325)","0","pure_quanta","I22";
;
LOCATION"R1654"
$SEC"1"
CDS_SEC"1"
WATTAGE"1/16W"
MATERIAL"CHIP"
VALUE"1K"
PACK_TYPE"0402LF"
TOLERANCE"1%"
PART_NUMBER"CS21002FB06"
BOM_COST"VR_SYSTEM "
REUSE_ID"3"
CDS_LIB"pure_quanta";
"A"
$PN"1"49;
"B"
$PN"2"55;
%"MOSFET_NCH_1D3S"
"1","(-4000,6900)","7","pure_quanta","I23";
;
LOCATION"Q57"
$SEC"1"
CDS_SEC"1"
VALUE"PSMNR58-30YLH"
PART_TYPE"SMLF"
MATERIAL"IC"
PART_NUMBER"BAMNR580000"
NEEDS_NO_SIZE"TRUE"
CDS_LMAN_SYM_OUTLINE"-150,200,150,-200"
CDS_LIB"pure_quanta";
"1"
$PN"1"40;
"4"
$PN"4"49;
"2"
$PN"2"40;
"5"
$PN"5"38;
"3"
$PN"3"40;
%"UNIVERSAL_POWER"
"1","(-7225,3900)","0","pure_quanta_power","I26";
;
HDL_POWER"P3V3"
BOM_COST"VR_SYSTEM "
CDS_LIB"pure_quanta_power";
"A"21;
%"BAT547F"
"1","(-6775,3625)","0","pure_quanta","I27";
;
LOCATION"D1"
$SEC"1"
CDS_SEC"1"
VALUE"BAT547F"
MATERIAL"IC"
PART_TYPE"SMLF"
PART_NUMBER"BC0BAT54Z53"
PIN_NAMES_ROTATE"TRUE"
NEEDS_NO_SIZE"TRUE"
BOM_COST"VR_SYSTEM "
CDS_LMAN_SYM_OUTLINE"-25,50,25,-50"
CDS_LIB"pure_quanta";
"3"
$PN"3"22;
"1"
$PN"1"21;
%"UNIVERSAL_POWER"
"1","(-6250,3900)","0","pure_quanta_power","I28";
;
HDL_POWER"P5V"
BOM_COST"VR_SYSTEM "
CDS_LIB"pure_quanta_power";
"A"22;
%"UNIVERSAL_GND"
"1","(-3950,6050)","0","pure_quanta_power","I37";
;
CDS_LIB"pure_quanta_power"
VOLTAGE"0"
BOM_COST"VR_SYSTEM "
HDL_POWER"GND";
"A"23;
%"Q_CAP"
"1","(-3950,6325)","0","pure_quanta","I38";
;
LOCATION"C9226"
$SEC"1"
CDS_SEC"1"
TOLERANCE"10%"
VOLTAGE"25V"
PACK_TYPE"C0402"
MATERIAL"X7R"
VALUE"0.22UF"
PART_NUMBER"CH4224K1B01"
CDS_LIB"pure_quanta";
"B"
$PN"2"23;
"A"
$PN"1"49;
%"Q_RES"
"1","(-6300,4950)","0","pure_quanta","I4";
;
LOCATION"R333"
$SEC"1"
CDS_SEC"1"
VALUE"0"
TOLERANCE"5%"
MATERIAL"CHIP"
PACK_TYPE"0402LF"
WATTAGE"1/16W"
PART_NUMBER"CS00002JB13"
CDS_LIB"pure_quanta"
BOM_COST"VR_SYSTEM ";
"B"
$PN"2"50;
"A"
$PN"1"56;
%"UNIVERSAL_GND"
"1","(-3375,7100)","0","pure_quanta_power","I40";
;
BOM_COST"VR_SYSTEM "
CDS_LIB"pure_quanta_power"
VOLTAGE"0"
HDL_POWER"GND";
"A"39;
%"Q_CAP"
"1","(-3375,7425)","0","pure_quanta","I41";
;
LOCATION"C1227"
$SEC"1"
CDS_SEC"1"
MATERIAL"X7R"
PACK_TYPE"C0402"
VALUE"100NF"
VOLTAGE"50V"
TOLERANCE"10%"
PART_NUMBER"CH4106K1B01"
CDS_LIB"pure_quanta"
BOM_COST"VR_SYSTEM "
REUSE_ID"81";
"B"
$PN"2"39;
"A"
$PN"1"40;
%"UNIVERSAL_POWER"
"1","(-3475,7900)","0","pure_quanta_power","I42";
;
HDL_POWER"P5V"
BOM_COST"VR_SYSTEM "
CDS_LIB"pure_quanta_power";
"A"40;
%"Q_CAP"
"1","(-3050,7425)","0","pure_quanta","I43";
;
LOCATION"C1331"
$SEC"1"
CDS_SEC"1"
VALUE"10UF"
VOLTAGE"16V"
TOLERANCE"10%"
MATERIAL"X6S"
PACK_TYPE"C0805"
PART_NUMBER"CH6103KEA00"
CDS_LIB"pure_quanta"
REUSE_ID"6"
BOM_COST"VR_SYSTEM ";
"B"
$PN"2"39;
"A"
$PN"1"40;
%"UNIVERSAL_GND"
"1","(-2350,6250)","0","pure_quanta_power","I44";
;
BOM_COST"VR_SYSTEM "
VOLTAGE"0"
CDS_LIB"pure_quanta_power"
HDL_POWER"GND";
"A"24;
%"Q_RES"
"2","(-2350,7275)","0","pure_quanta","I45";
;
LOCATION"R4638"
$SEC"1"
CDS_SEC"1"
TOLERANCE"1%"
WATTAGE"1/4W"
MATERIAL"CHIP"
VALUE"243"
PACK_TYPE"1206LF"
PART_NUMBER"CS12436F201"
CDS_LIB"pure_quanta";
"A"
$PN"1"40;
"B"
$PN"2"47;
%"UNIVERSAL_GND"
"1","(-1225,5375)","0","pure_quanta_power","I46";
;
VOLTAGE"0"
CDS_LIB"pure_quanta_power"
BOM_COST"VR_SYSTEM "
HDL_POWER"GND";
"A"41;
%"Q_CAP"
"1","(-1225,5700)","2","pure_quanta","I48";
;
LOCATION"C1332"
$SEC"1"
CDS_SEC"1"
PACK_TYPE"C0402"
VALUE"100NF"
TOLERANCE"10%"
VOLTAGE"50V"
MATERIAL"X7R"
PART_NUMBER"CH4106K1B01"
BOM_COST"VR_SYSTEM "
CDS_LIB"pure_quanta";
"B"
$PN"2"41;
"A"
$PN"1"42;
%"Q_CAP"
"1","(-900,5700)","2","pure_quanta","I49";
;
LOCATION"C1333"
$SEC"1"
CDS_SEC"1"
VOLTAGE"16V"
TOLERANCE"10%"
PACK_TYPE"C0805"
VALUE"10UF"
MATERIAL"X6S"
PART_NUMBER"CH6103KEA00"
BOM_COST"VR_SYSTEM "
CDS_LIB"pure_quanta";
"B"
$PN"2"41;
"A"
$PN"1"42;
%"MOSFET_NCH_1D3S"
"1","(75,5250)","7","pure_quanta","I50";
;
LOCATION"Q56"
$SEC"1"
CDS_SEC"1"
VALUE"PSMNR58-30YLH"
PART_TYPE"SMLF"
MATERIAL"IC"
PART_NUMBER"BAMNR580000"
NEEDS_NO_SIZE"TRUE"
CDS_LMAN_SYM_OUTLINE"-150,200,150,-200"
CDS_LIB"pure_quanta";
"1"
$PN"1"44;
"4"
$PN"4"60;
"2"
$PN"2"44;
"5"
$PN"5"42;
"3"
$PN"3"44;
%"Q_CAP"
"1","(-500,5700)","2","pure_quanta","I51";
;
LOCATION"C60"
$SEC"1"
CDS_SEC"1"
MATERIAL"EMPTY"
TOLERANCE"10%"
PACK_TYPE"C0805"
VALUE"10UF"
VOLTAGE"16V"
PART_NUMBER"CH6103KEA00"
BOM_COST"VR_SYSTEM "
CDS_LIB"pure_quanta";
"B"
$PN"2"41;
"A"
$PN"1"42;
%"P1V0_AUX"
"1","(-326,6099)","0","pure_quanta_power","I52";
;
HDL_POWER"P3V3_AUX"
BOM_COST"VR_SYSTEM "
CDS_LIB"pure_quanta_power";
"A"42;
%"UNIVERSAL_GND"
"1","(1100,5350)","0","pure_quanta_power","I58";
;
BOM_COST"VR_SYSTEM "
CDS_LIB"pure_quanta_power"
VOLTAGE"0"
HDL_POWER"GND";
"A"43;
%"Q_CAP"
"1","(725,5700)","0","pure_quanta","I59";
;
LOCATION"C61"
$SEC"1"
CDS_SEC"1"
PACK_TYPE"C0402"
VOLTAGE"50V"
TOLERANCE"10%"
MATERIAL"X7R"
VALUE"100NF"
PART_NUMBER"CH4106K1B01"
BOM_COST"VR_SYSTEM "
CDS_LIB"pure_quanta";
"B"
$PN"2"43;
"A"
$PN"1"44;
%"UNIVERSAL_GND"
"1","(-5775,4300)","0","pure_quanta_power","I6";
;
BOM_COST"VR_SYSTEM "
VOLTAGE"0"
CDS_LIB"pure_quanta_power"
HDL_POWER"GND";
"A"25;
%"UNIVERSAL_POWER"
"1","(625,6100)","0","pure_quanta_power","I60";
;
HDL_POWER"P3V3"
BOM_COST"VR_SYSTEM "
CDS_LIB"pure_quanta_power";
"A"44;
%"Q_CAP"
"1","(1100,5700)","0","pure_quanta","I61";
;
LOCATION"C1340"
$SEC"1"
CDS_SEC"1"
PACK_TYPE"C0805"
TOLERANCE"10%"
MATERIAL"X6S"
VOLTAGE"16V"
VALUE"10UF"
PART_NUMBER"CH6103KEA00"
BOM_COST"VR_SYSTEM "
CDS_LIB"pure_quanta";
"B"
$PN"2"43;
"A"
$PN"1"44;
%"MOSFET_NCH_GDS_ESD_PROTECTED"
"1","(-2375,6625)","0","pure_quanta","I62";
;
LOCATION"U324"
$SEC"1"
CDS_SEC"1"
MATERIAL"IC"
VALUE"2N7002K"
PART_TYPE"SMLF"
PART_NUMBER"BAM70020002"
CDS_LIB"pure_quanta"
CDS_LMAN_SYM_OUTLINE"-125,150,125,-150"
NEEDS_NO_SIZE"TRUE";
"S"
$PN"S"24;
"G"
$PN"G"62;
"D"
$PN"D"47;
%"Q_RES"
"2","(-5775,4675)","0","pure_quanta","I7";
;
LOCATION"R334"
$SEC"1"
CDS_SEC"1"
MATERIAL"CHIP"
WATTAGE"1/16W"
TOLERANCE"1%"
PACK_TYPE"0402LF"
VALUE"100K"
PART_NUMBER"CS41002FB09"
CDS_LIB"pure_quanta";
"A"
$PN"1"50;
"B"
$PN"2"25;
%"Q_RES"
"2","(-1750,7275)","0","pure_quanta","I74";
;
LOCATION"R4639"
$SEC"1"
CDS_SEC"1"
PACK_TYPE"1206LF"
MATERIAL"CHIP"
WATTAGE"1/4W"
TOLERANCE"1%"
VALUE"243"
PART_NUMBER"CS12436F201"
CDS_LIB"pure_quanta";
"A"
$PN"1"40;
"B"
$PN"2"47;
%"Q_RES"
"2","(-1175,7275)","0","pure_quanta","I75";
;
LOCATION"R4640"
$SEC"1"
CDS_SEC"1"
WATTAGE"1/4W"
MATERIAL"CHIP"
VALUE"243"
TOLERANCE"1%"
PACK_TYPE"1206LF"
PART_NUMBER"CS12436F201"
CDS_LIB"pure_quanta";
"A"
$PN"1"40;
"B"
$PN"2"47;
%"Q_RES"
"2","(-600,7275)","0","pure_quanta","I76";
;
LOCATION"R4641"
$SEC"1"
CDS_SEC"1"
PACK_TYPE"1206LF"
MATERIAL"CHIP"
TOLERANCE"1%"
VALUE"243"
WATTAGE"1/4W"
PART_NUMBER"CS12436F201"
CDS_LIB"pure_quanta";
"A"
$PN"1"40;
"B"
$PN"2"47;
%"RT9818C44GV"
"1","(-3750,3875)","2","pure_quanta","I77";
;
LOCATION"U100"
SEC"1"
MATERIAL"IC"
VALUE"RT9818C-44GV"
PART_TYPE"SMLF"
PART_NUMBER"AL009818001"
SEC_TYPE""
CDS_LMAN_SYM_OUTLINE"-225,200,225,-200"
PIN_NAMES_ROTATE"True"
CDS_LIB"pure_quanta";
"GND"
$PN"2"28;
"RESET# \B"
$PN"1"33;
"VDD"
$PN"3"45;
%"UNIVERSAL_POWER"
"1","(-4275,4250)","0","pure_quanta_power","I78";
;
HDL_POWER"P5V"
CDS_LIB"pure_quanta_power"
BOM_COST"VR_SYSTEM ";
"A"45;
%"Q_CAP"
"1","(-4275,3525)","0","pure_quanta","I79";
;
LOCATION"C6122"
$SEC"1"
CDS_SEC"1"
VALUE"100NF"
VOLTAGE"50V"
TOLERANCE"10%"
MATERIAL"X7R"
PACK_TYPE"C0402"
PART_NUMBER"CH4106K1B01"
CDS_LIB"pure_quanta";
"B"
$PN"2"27;
"A"
$PN"1"45;
%"UNIVERSAL_GND"
"1","(-5125,4525)","0","pure_quanta_power","I8";
;
CDS_LIB"pure_quanta_power"
BOM_COST"VR_SYSTEM "
VOLTAGE"0"
HDL_POWER"GND";
"A"26;
%"UNIVERSAL_GND"
"1","(-4275,3150)","0","pure_quanta_power","I80";
;
VOLTAGE"0"
BOM_COST"VR_SYSTEM "
CDS_LIB"pure_quanta_power"
HDL_POWER"GND";
"A"27;
%"UNIVERSAL_GND"
"1","(-3300,3475)","0","pure_quanta_power","I81";
;
CDS_LIB"pure_quanta_power"
BOM_COST"VR_SYSTEM "
VOLTAGE"0"
HDL_POWER"GND";
"A"28;
%"Q_RES"
"2","(-2875,4250)","0","pure_quanta","I83";
;
LOCATION"R479"
SEC"1"
WATTAGE"1/16W"
VALUE"10K"
TOLERANCE"1%"
MATERIAL"CHIP"
PACK_TYPE"0402LF"
PART_NUMBER"CS31002FB08"
CDS_LIB"pure_quanta"
SEC_TYPE"0402LF";
"A"
$PN"1"29;
"B"
$PN"2"33;
%"Q_RES"
"2","(-2800,3725)","2","pure_quanta","I84";
;
LOCATION"R480"
SEC"1"
TOLERANCE"1%"
VALUE"100K"
WATTAGE"1/16W"
MATERIAL"CHIP"
PACK_TYPE"0402LF"
PART_NUMBER"CS41002FB09"
SEC_TYPE"0402LF"
CDS_LIB"pure_quanta";
"A"
$PN"1"33;
"B"
$PN"2"30;
%"UNIVERSAL_POWER"
"1","(-2875,4550)","0","pure_quanta_power","I85";
;
HDL_POWER"P5V"
CDS_LIB"pure_quanta_power"
BOM_COST"VR_SYSTEM ";
"A"29;
%"UNIVERSAL_GND"
"1","(-2800,3450)","0","pure_quanta_power","I86";
;
VOLTAGE"0"
BOM_COST"VR_SYSTEM "
CDS_LIB"pure_quanta_power"
HDL_POWER"GND";
"A"30;
%"Q_RES"
"1","(-2275,3975)","0","pure_quanta","I88";
;
LOCATION"R490"
SEC"1"
TOLERANCE"5%"
MATERIAL"EMPTY"
VALUE"0"
PACK_TYPE"0402LF"
PART_NUMBER"CS00002JB13"
SEC_TYPE"0402LF"
WATTAGE"1/16W"
CDS_LIB"pure_quanta";
"B"
$PN"2"48;
"A"
$PN"1"33;
%"MOSFET_NCH_DUAL"
"1","(-5175,5000)","0","pure_quanta","I9";
;
LOCATION"Q37"
$SEC"1"
CDS_SEC"1"
PART_TYPE"SMLF"
MATERIAL"IC"
VALUE"PJT138K"
PART_NUMBER"BAM138K0003"
NEEDS_NO_SIZE"TRUE"
CDS_LMAN_SYM_OUTLINE"-150,150,150,-150"
CDS_LIB"pure_quanta";
"D1"
$PN"6"51;
"G1"
$PN"2"50;
"S1"
$PN"1"26;
%"Q_RES"
"2","(-3200,4575)","2","pure_quanta","I91";
;
LOCATION"R6050"
SEC"1"
TOLERANCE"1%"
VALUE"100K"
MATERIAL"EMPTY"
PACK_TYPE"0402LF"
PART_NUMBER"CS41002FB09"
WATTAGE"1/16W"
CDS_LIB"pure_quanta"
SEC_TYPE"0402LF";
"A"
$PN"1"46;
"B"
$PN"2"31;
%"UNIVERSAL_GND"
"1","(-3200,4350)","0","pure_quanta_power","I92";
;
BOM_COST"VR_SYSTEM "
VOLTAGE"0"
CDS_LIB"pure_quanta_power"
HDL_POWER"GND";
"A"31;
%"Q_RES"
"2","(-3175,5075)","0","pure_quanta","I93";
;
LOCATION"R496"
$SEC"1"
CDS_SEC"1"
PACK_TYPE"0402LF"
VALUE"10K"
MATERIAL"EMPTY"
WATTAGE"1/16W"
TOLERANCE"1%"
PART_NUMBER"CS31002FB08"
CDS_LIB"pure_quanta";
"A"
$PN"1"32;
"B"
$PN"2"46;
%"P1V0_AUX"
"1","(-3175,5350)","0","pure_quanta_power","I94";
;
HDL_POWER"P3V3_AUX"
BOM_COST"VR_SYSTEM "
CDS_LIB"pure_quanta_power";
"A"32;
%"Q_RES"
"1","(-2475,4775)","0","pure_quanta","I95";
;
LOCATION"R487"
SEC"1"
PACK_TYPE"0402LF"
VALUE"0"
MATERIAL"CHIP"
TOLERANCE"5%"
PART_NUMBER"CS00002JB13"
CDS_LIB"pure_quanta"
SEC_TYPE"0402LF"
WATTAGE"1/16W";
"B"
$PN"2"48;
"A"
$PN"1"46;
%"Q_RES"
"1","(-2500,2500)","0","pure_quanta","I96";
;
LOCATION"R482"
SEC"1"
VALUE"0"
TOLERANCE"5%"
PACK_TYPE"0402LF"
MATERIAL"CHIP"
PART_NUMBER"CS00002JB13"
WATTAGE"1/16W"
CDS_LIB"pure_quanta"
SEC_TYPE"0402LF";
"B"
$PN"2"34;
"A"
$PN"1"33;
%"MOSFET_NCH_DUAL"
"1","(-1500,2550)","0","pure_quanta","I97";
;
LOCATION"Q1"
SEC"1"
VALUE"PJT138K"
PART_TYPE"SMLF"
MATERIAL"IC"
PART_NUMBER"BAM138K0003"
SEC_TYPE""
CDS_LIB"pure_quanta"
NEEDS_NO_SIZE"TRUE"
CDS_LMAN_SYM_OUTLINE"-150,150,150,-150";
"D1"
$PN"6"61;
"G1"
$PN"2"34;
"S1"
$PN"1"2;
%"MOSFET_NCH_DUAL"
"2","(250,2900)","0","pure_quanta","I98";
;
LOCATION"Q1"
SEC"2"
PART_TYPE"SMLF"
VALUE"PJT138K"
MATERIAL"IC"
PART_NUMBER"BAM138K0003"
CDS_LMAN_SYM_OUTLINE"-150,150,150,-150"
NEEDS_NO_SIZE"TRUE"
CDS_LIB"pure_quanta"
SEC_TYPE"";
"S2"
$PN"4"3;
"G2"
$PN"5"57;
"D2"
$PN"3"58;
%"Q_RES"
"2","(-1450,3000)","2","pure_quanta","I99";
;
LOCATION"R492"
SEC"1"
PACK_TYPE"0402LF"
MATERIAL"CHIP"
WATTAGE"1/16W"
TOLERANCE"5%"
VALUE"4.7K"
PART_NUMBER"CS24702JB10"
CDS_LIB"pure_quanta"
SEC_TYPE"0402LF";
"A"
$PN"1"1;
"B"
$PN"2"61;
END.
